FILE_TYPE = MULTI_PHYS_TABLE;
PART 'NCP3232L'
{===========================================================================================================================================================================}
: PACK_TYPE | MATERIAL | PART_NUMBER     = EnvComp | PART_NUMBER  | JEDEC_TYPE     | CLASS | DESCRIPTION                  | COMPONENT_TYPE | HEIGHT        | LPID   | SPEED_URL | Status |RPL| AML | Bus_Unit | Days;
{===========================================================================================================================================================================}
'SM'        | 'IC'     | 'H86355-001'(!) = ''      | 'H86355-001' | 'LCC40_24_5ME' | 'IC'  | 'IC,LIN,QFN,NCP3232L,DC/DC'  | 'LCC'          | '0.039 IN'    | '1960' | 'http://speed.intel.com:8081/speed/module/pdm/item/pdm_item_detail_direct.asp?item_cde=H86355-001&item_rev=01&url_param=unused' | '' | '' | '' | '' | '' 
'SM'        | 'EMPTY'  | 'H86355-001'(!) = ''      | 'H86355-001' | 'LCC40_24_5ME' | 'IO'  | 'IC,LIN,QFN,NCP3232L,DC/DC'  | 'LCC'          | '0.039 IN'    | '1960' | 'http://speed.intel.com:8081/speed/module/pdm/item/pdm_item_detail_direct.asp?item_cde=H86355-001&item_rev=01&url_param=unused' | '' | '' | '' | '' | ''  
END_PART
END.
